# TIMECARD (Time Appliance Project (Time Card)) — schematic netlist excerpt (pin names and nets, part order shuffled) for the footprints in the layout excerpt that follows; sources: Cadence DE-HDL packaged netlist, KiCad conversion of R4006-B0001-02_R01.brd

R134  RESISTOR  33OHM 1%  pkg SMC_0402R_H016  page 10 : \1\ = FT4232_FPGA_TCK ; \2\ = FPGA_TCK
R43  RESISTOR  0OHM -  pkg SMC_0402R_H016  page 9 : \1\ = PCIE_CONN_TMS ; \2\ = FPGA_TMS

(kicad_pcb
	(version 20260206)
	(generator "pcbnew")
	(generator_version "10.0")
	(general
		(thickness 1.6)
		(legacy_teardrops no)
	)
	(paper "A4")
	(title_block
		(title "timecard-production-celestica-r4006 — R4006-B0001-02_R01.brd")
		(comment 1 "Time Appliance Project (Time Card) / footprints 673-674 of 1113")
	)
	(layers
		(0 "F.Cu" signal "TOP")
		(4 "In1.Cu" signal "L02_GND1")
		(6 "In2.Cu" signal "L03_SIG1")
		(8 "In3.Cu" signal "L04_GND2")
		(10 "In4.Cu" signal "L05_VCC1")
		(12 "In5.Cu" signal "L06_VCC2")
		(14 "In6.Cu" signal "L07_GND3")
		(16 "In7.Cu" signal "L08_SIG2")
		(18 "In8.Cu" signal "L09_GND4")
		(2 "B.Cu" signal "BOTTOM")
		(9 "F.Adhes" user "F.Adhesive")
		(11 "B.Adhes" user "B.Adhesive")
		(13 "F.Paste" user "Package Geometry/Pastemask Top")
		(15 "B.Paste" user "Package Geometry/Pastemask Bottom")
		(5 "F.SilkS" user "Ref Des/Silkscreen Top")
		(7 "B.SilkS" user "Ref Des/Silkscreen Bottom")
		(1 "F.Mask" user "Board Geometry/Soldermask Top")
		(3 "B.Mask" user "Board Geometry/Soldermask Bottom")
		(17 "Dwgs.User" user "User.Drawings")
		(19 "Cmts.User" user "User.Comments")
		(21 "Eco1.User" user "User.Eco1")
		(23 "Eco2.User" user "User.Eco2")
		(25 "Edge.Cuts" user "Board Geometry/Outline")
		(27 "Margin" user)
		(31 "F.CrtYd" user "Package Geometry/Place Bound Top")
		(29 "B.CrtYd" user "Package Geometry/Place Bound Bottom")
		(35 "F.Fab" user "Ref Des/Assembly Top")
		(33 "B.Fab" user "Ref Des/Assembly Bottom")
	)
	(footprint ""
		(layer "B.Cu")
		(at 139.065 -72.898 180)
		(property "Reference" "R43"
			(at 2.286 0.21463 0)
			(unlocked yes)
			(layer "B.SilkS")
			(effects
				(font
					(size 0.7874 0.5842)
					(thickness 0.1524)
				)
				(justify mirror)
			)
		)
		(property "Value" "VAL*"
			(at -0.02032 2.13233 180)
			(unlocked yes)
			(layer "B.Fab")
			(hide yes)
			(effects
				(font
					(size 0.7874 0.5842)
					(thickness 0.1524)
				)
				(justify mirror)
			)
		)
		(property "Tolerance" "TOL*"
			(at -0.044704 3.05435 180)
			(unlocked yes)
			(layer "Cmts.User")
			(hide yes)
			(effects
				(font
					(size 0.7874 0.5842)
					(thickness 0.1524)
				)
				(justify mirror)
			)
		)
		(property "User Part Number" "PARTNUM*"
			(at -0.02032 4.024884 180)
			(unlocked yes)
			(layer "Cmts.User")
			(hide yes)
			(effects
				(font
					(size 0.7874 0.5842)
					(thickness 0.1524)
				)
				(justify mirror)
			)
		)
		(property "Device Type" "RESISTOR-G155-100R0-J0,0OHM,-"
			(at -0.008382 1.210564 180)
			(unlocked yes)
			(layer "B.Fab")
			(hide yes)
			(effects
				(font
					(size 0.7874 0.5842)
					(thickness 0.1524)
				)
				(justify mirror)
			)
		)
		(duplicate_pad_numbers_are_jumpers no)
		(fp_line
			(start 1.143 0.5588)
			(end -1.143 0.5588)
			(stroke
				(width 0.1)
				(type default)
			)
			(layer "B.SilkS")
		)
		(fp_line
			(start 1.143 -0.5588)
			(end 1.143 0.5588)
			(stroke
				(width 0.1)
				(type default)
			)
			(layer "B.SilkS")
		)
		(fp_line
			(start -1.143 0.5588)
			(end -1.143 -0.5588)
			(stroke
				(width 0.1)
				(type default)
			)
			(layer "B.SilkS")
		)
		(fp_line
			(start -1.143 -0.5588)
			(end 1.143 -0.5588)
			(stroke
				(width 0.1)
				(type default)
			)
			(layer "B.SilkS")
		)
		(fp_rect
			(start 1.143 0.5588)
			(end -1.143 -0.5588)
			(stroke
				(width 0)
				(type default)
			)
			(fill no)
			(layer "B.CrtYd")
		)
		(fp_line
			(start 0.508 0.3048)
			(end -0.508 0.3048)
			(stroke
				(width 0.1)
				(type default)
			)
			(layer "B.Fab")
		)
		(fp_line
			(start 0.508 -0.3048)
			(end 0.508 0.3048)
			(stroke
				(width 0.1)
				(type default)
			)
			(layer "B.Fab")
		)
		(fp_line
			(start -0.508 0.3048)
			(end -0.508 -0.3048)
			(stroke
				(width 0.1)
				(type default)
			)
			(layer "B.Fab")
		)
		(fp_line
			(start -0.508 -0.3048)
			(end 0.508 -0.3048)
			(stroke
				(width 0.1)
				(type default)
			)
			(layer "B.Fab")
		)
		(pad "1" smd rect
			(at 0.5334 0)
			(size 0.7112 0.6096)
			(layers "B.Cu" "B.Mask" "B.Paste")
			(net "PCIE_CONN_TMS")
		)
		(pad "2" smd rect
			(at -0.5334 0)
			(size 0.7112 0.6096)
			(layers "B.Cu" "B.Mask" "B.Paste")
			(net "FPGA_TMS")
		)
		(zone
			(layer "B.Cu")
			(hatch none 0.5)
			(connect_pads
				(clearance 0)
			)
			(min_thickness 0.25)
			(keepout
				(tracks allowed)
				(vias not_allowed)
				(pads allowed)
				(copperpour not_allowed)
				(footprints allowed)
			)
			(placement
				(enabled no)
				(sheetname "")
			)
			(fill
				(thermal_gap 0.5)
				(thermal_bridge_width 0.5)
				(island_removal_mode 0)
			)
			(polygon
				(pts
					(xy 138.9888 -73.2028) (xy 138.9888 -72.5932) (xy 139.1412 -72.5932) (xy 139.1412 -73.2028)
				)
			)
		)
	)
	(footprint ""
		(layer "B.Cu")
		(at 140.335 -67.056)
		(property "Reference" "R134"
			(at 1.73863 -1.143 270)
			(unlocked yes)
			(layer "B.SilkS")
			(effects
				(font
					(size 0.7874 0.5842)
					(thickness 0.1524)
				)
				(justify mirror)
			)
		)
		(property "Value" "VAL*"
			(at -0.02032 2.13233 0)
			(unlocked yes)
			(layer "B.Fab")
			(hide yes)
			(effects
				(font
					(size 0.7874 0.5842)
					(thickness 0.1524)
				)
				(justify mirror)
			)
		)
		(property "Tolerance" "TOL*"
			(at -0.044704 3.05435 0)
			(unlocked yes)
			(layer "Cmts.User")
			(hide yes)
			(effects
				(font
					(size 0.7874 0.5842)
					(thickness 0.1524)
				)
				(justify mirror)
			)
		)
		(property "User Part Number" "PARTNUM*"
			(at -0.02032 4.024884 0)
			(unlocked yes)
			(layer "Cmts.User")
			(hide yes)
			(effects
				(font
					(size 0.7874 0.5842)
					(thickness 0.1524)
				)
				(justify mirror)
			)
		)
		(property "Device Type" "RESISTOR-G155-133R0-01,33OHM,1%"
			(at -0.008382 1.210564 0)
			(unlocked yes)
			(layer "B.Fab")
			(hide yes)
			(effects
				(font
					(size 0.7874 0.5842)
					(thickness 0.1524)
				)
				(justify mirror)
			)
		)
		(duplicate_pad_numbers_are_jumpers no)
		(fp_line
			(start -1.143 -0.5588)
			(end 1.143 -0.5588)
			(stroke
				(width 0.1)
				(type default)
			)
			(layer "B.SilkS")
		)
		(fp_line
			(start -1.143 0.5588)
			(end -1.143 -0.5588)
			(stroke
				(width 0.1)
				(type default)
			)
			(layer "B.SilkS")
		)
		(fp_line
			(start 1.143 -0.5588)
			(end 1.143 0.5588)
			(stroke
				(width 0.1)
				(type default)
			)
			(layer "B.SilkS")
		)
		(fp_line
			(start 1.143 0.5588)
			(end -1.143 0.5588)
			(stroke
				(width 0.1)
				(type default)
			)
			(layer "B.SilkS")
		)
		(fp_rect
			(start -1.143 -0.5588)
			(end 1.143 0.5588)
			(stroke
				(width 0)
				(type default)
			)
			(fill no)
			(layer "B.CrtYd")
		)
		(fp_line
			(start -0.508 -0.3048)
			(end 0.508 -0.3048)
			(stroke
				(width 0.1)
				(type default)
			)
			(layer "B.Fab")
		)
		(fp_line
			(start -0.508 0.3048)
			(end -0.508 -0.3048)
			(stroke
				(width 0.1)
				(type default)
			)
			(layer "B.Fab")
		)
		(fp_line
			(start 0.508 -0.3048)
			(end 0.508 0.3048)
			(stroke
				(width 0.1)
				(type default)
			)
			(layer "B.Fab")
		)
		(fp_line
			(start 0.508 0.3048)
			(end -0.508 0.3048)
			(stroke
				(width 0.1)
				(type default)
			)
			(layer "B.Fab")
		)
		(pad "1" smd rect
			(at 0.5334 0 180)
			(size 0.7112 0.6096)
			(layers "B.Cu" "B.Mask" "B.Paste")
			(net "FT4232_FPGA_TCK")
		)
		(pad "2" smd rect
			(at -0.5334 0 180)
			(size 0.7112 0.6096)
			(layers "B.Cu" "B.Mask" "B.Paste")
			(net "FPGA_TCK")
		)
		(zone
			(layer "B.Cu")
			(hatch none 0.5)
			(connect_pads
				(clearance 0)
			)
			(min_thickness 0.25)
			(keepout
				(tracks allowed)
				(vias not_allowed)
				(pads allowed)
				(copperpour not_allowed)
				(footprints allowed)
			)
			(placement
				(enabled no)
				(sheetname "")
			)
			(fill
				(thermal_gap 0.5)
				(thermal_bridge_width 0.5)
				(island_removal_mode 0)
			)
			(polygon
				(pts
					(xy 140.2588 -67.3608) (xy 140.2588 -66.7512) (xy 140.4112 -66.7512) (xy 140.4112 -67.3608)
				)
			)
		)
	)
)
